# S9S_MB_2U (Grand Teton) — schematic netlist excerpt (pin names and nets, part order shuffled) for the footprints in the layout excerpt that follows; sources: Cadence DE-HDL packaged netlist, KiCad conversion of 03242023_DA0F0TMBIJ0_F0T_Motherboard_J_brd_V01_OCP.brd

PR1802  Q_RES  3.3 1% CHIP  pkg 0402LF  page 290 : A = SW_PVCCFA_EHV_FIVRA_CPU1_BOOT3 ; B = SW_PVCCFA_EHV_FIVRA_CPU1_BOOT3_
PC606  Q_CAP  100NF 50V 10% X7R  pkg C0402  page 271 : A = SW_PVCCFA_EHV_FIVRA_CPU0_BOOT1_ ; B = SW_PVCCFA_EHV_FIVRA_CPU0_BOOTR1

(kicad_pcb
	(version 20260206)
	(generator "pcbnew")
	(generator_version "10.0")
	(general
		(thickness 1.6)
		(legacy_teardrops no)
	)
	(paper "A4")
	(title_block
		(title "03242023_DA0F0TMBIJ0_F0T_Motherboard_J_brd_V01_OCP.brd")
		(comment 1 "Grand Teton / footprints 1280-1281 of 6105")
	)
	(layers
		(0 "F.Cu" signal "TOP")
		(4 "In1.Cu" signal "GND")
		(6 "In2.Cu" signal "IN1")
		(8 "In3.Cu" signal "GND1")
		(10 "In4.Cu" signal "IN2")
		(12 "In5.Cu" signal "GND2")
		(14 "In6.Cu" signal "IN3")
		(16 "In7.Cu" signal "GND3")
		(18 "In8.Cu" signal "VCC")
		(20 "In9.Cu" signal "VCC1")
		(22 "In10.Cu" signal "GND4")
		(24 "In11.Cu" signal "IN4")
		(26 "In12.Cu" signal "GND5")
		(28 "In13.Cu" signal "IN5")
		(30 "In14.Cu" signal "GND6")
		(32 "In15.Cu" signal "IN6")
		(34 "In16.Cu" signal "GND7")
		(2 "B.Cu" signal "BOTTOM")
		(9 "F.Adhes" user "F.Adhesive")
		(11 "B.Adhes" user "B.Adhesive")
		(13 "F.Paste" user "Package Geometry/Pastemask Top")
		(15 "B.Paste" user "Package Geometry/Pastemask Bottom")
		(5 "F.SilkS" user "Ref Des/Silkscreen Top")
		(7 "B.SilkS" user "Ref Des/Silkscreen Bottom")
		(1 "F.Mask" user "Board Geometry/Soldermask Top")
		(3 "B.Mask" user "Board Geometry/Soldermask Bottom")
		(17 "Dwgs.User" user "User.Drawings")
		(19 "Cmts.User" user "User.Comments")
		(21 "Eco1.User" user "User.Eco1")
		(23 "Eco2.User" user "User.Eco2")
		(25 "Edge.Cuts" user "Board Geometry/Outline")
		(27 "Margin" user)
		(31 "F.CrtYd" user "Package Geometry/Place Bound Top")
		(29 "B.CrtYd" user "Package Geometry/Place Bound Bottom")
		(35 "F.Fab" user "Ref Des/Assembly Top")
		(33 "B.Fab" user "Ref Des/Assembly Bottom")
	)
	(footprint ""
		(layer "F.Cu")
		(at 182.471822 -358.15778 90)
		(property "Reference" "PR1802"
			(at 0 0 90)
			(layer "F.SilkS")
			(hide yes)
			(effects
				(font
					(size 1.27 1.27)
				)
			)
		)
		(property "Value" ""
			(at 0 0 90)
			(layer "F.Fab")
			(effects
				(font
					(size 1.27 1.27)
				)
			)
		)
		(duplicate_pad_numbers_are_jumpers no)
		(fp_line
			(start 0.7874 -0.4064)
			(end 0.7874 0.4064)
			(stroke
				(width 0.1524)
				(type default)
			)
			(layer "F.SilkS")
		)
		(fp_line
			(start -0.7874 -0.4064)
			(end 0.7874 -0.4064)
			(stroke
				(width 0.1524)
				(type default)
			)
			(layer "F.SilkS")
		)
		(fp_line
			(start 0.7874 0.4064)
			(end -0.7874 0.4064)
			(stroke
				(width 0.1524)
				(type default)
			)
			(layer "F.SilkS")
		)
		(fp_line
			(start -0.7874 0.4064)
			(end -0.7874 -0.4064)
			(stroke
				(width 0.1524)
				(type default)
			)
			(layer "F.SilkS")
		)
		(fp_line
			(start -0.12065 -0.305054)
			(end -0.12065 -0.2794)
			(stroke
				(width 0.1)
				(type default)
			)
			(layer "F.Fab")
		)
		(fp_line
			(start -0.67945 -0.305054)
			(end -0.12065 -0.305054)
			(stroke
				(width 0.1)
				(type default)
			)
			(layer "F.Fab")
		)
		(fp_line
			(start 0.67945 -0.3048)
			(end 0.67945 0.3048)
			(stroke
				(width 0.1)
				(type default)
			)
			(layer "F.Fab")
		)
		(fp_line
			(start 0.12065 -0.3048)
			(end 0.67945 -0.3048)
			(stroke
				(width 0.1)
				(type default)
			)
			(layer "F.Fab")
		)
		(fp_line
			(start 0.12065 -0.2794)
			(end 0.12065 -0.3048)
			(stroke
				(width 0.1)
				(type default)
			)
			(layer "F.Fab")
		)
		(fp_line
			(start -0.12065 -0.2794)
			(end 0.12065 -0.2794)
			(stroke
				(width 0.1)
				(type default)
			)
			(layer "F.Fab")
		)
		(fp_line
			(start 0.120396 0.2794)
			(end -0.12065 0.2794)
			(stroke
				(width 0.1)
				(type default)
			)
			(layer "F.Fab")
		)
		(fp_line
			(start -0.12065 0.2794)
			(end -0.12065 0.3048)
			(stroke
				(width 0.1)
				(type default)
			)
			(layer "F.Fab")
		)
		(fp_line
			(start 0.67945 0.3048)
			(end 0.120396 0.3048)
			(stroke
				(width 0.1)
				(type default)
			)
			(layer "F.Fab")
		)
		(fp_line
			(start 0.120396 0.3048)
			(end 0.120396 0.2794)
			(stroke
				(width 0.1)
				(type default)
			)
			(layer "F.Fab")
		)
		(fp_line
			(start -0.12065 0.3048)
			(end -0.67945 0.3048)
			(stroke
				(width 0.1)
				(type default)
			)
			(layer "F.Fab")
		)
		(fp_line
			(start -0.67945 0.3048)
			(end -0.67945 -0.305054)
			(stroke
				(width 0.1)
				(type default)
			)
			(layer "F.Fab")
		)
		(pad "1" smd circle
			(at -0.40005 0 90)
			(size 0 0)
			(layers "F.Cu" "F.Mask" "F.Paste")
			(net "SW_PVCCFA_EHV_FIVRA_CPU1_BOOT3")
		)
		(pad "2" smd circle
			(at 0.40005 0 90)
			(size 0 0)
			(layers "F.Cu" "F.Mask" "F.Paste")
			(net "SW_PVCCFA_EHV_FIVRA_CPU1_BOOT3_")
		)
	)
	(footprint ""
		(layer "F.Cu")
		(at 417.946332 -366.691164 -90)
		(property "Reference" "PC606"
			(at 0 0 270)
			(layer "F.SilkS")
			(hide yes)
			(effects
				(font
					(size 1.27 1.27)
				)
			)
		)
		(property "Value" ""
			(at 0 0 270)
			(layer "F.Fab")
			(effects
				(font
					(size 1.27 1.27)
				)
			)
		)
		(duplicate_pad_numbers_are_jumpers no)
		(fp_line
			(start -0.7874 0.4064)
			(end -0.7874 -0.4064)
			(stroke
				(width 0.1524)
				(type default)
			)
			(layer "F.SilkS")
		)
		(fp_line
			(start 0.7874 0.4064)
			(end -0.7874 0.4064)
			(stroke
				(width 0.1524)
				(type default)
			)
			(layer "F.SilkS")
		)
		(fp_line
			(start -0.7874 -0.4064)
			(end 0.7874 -0.4064)
			(stroke
				(width 0.1524)
				(type default)
			)
			(layer "F.SilkS")
		)
		(fp_line
			(start 0.7874 -0.4064)
			(end 0.7874 0.4064)
			(stroke
				(width 0.1524)
				(type default)
			)
			(layer "F.SilkS")
		)
		(fp_line
			(start -0.67945 0.3048)
			(end -0.67945 -0.305054)
			(stroke
				(width 0.1)
				(type default)
			)
			(layer "F.Fab")
		)
		(fp_line
			(start -0.12065 0.3048)
			(end -0.67945 0.3048)
			(stroke
				(width 0.1)
				(type default)
			)
			(layer "F.Fab")
		)
		(fp_line
			(start 0.120396 0.3048)
			(end 0.120396 0.2794)
			(stroke
				(width 0.1)
				(type default)
			)
			(layer "F.Fab")
		)
		(fp_line
			(start 0.67945 0.3048)
			(end 0.120396 0.3048)
			(stroke
				(width 0.1)
				(type default)
			)
			(layer "F.Fab")
		)
		(fp_line
			(start -0.12065 0.2794)
			(end -0.12065 0.3048)
			(stroke
				(width 0.1)
				(type default)
			)
			(layer "F.Fab")
		)
		(fp_line
			(start 0.120396 0.2794)
			(end -0.12065 0.2794)
			(stroke
				(width 0.1)
				(type default)
			)
			(layer "F.Fab")
		)
		(fp_line
			(start -0.12065 -0.2794)
			(end 0.12065 -0.2794)
			(stroke
				(width 0.1)
				(type default)
			)
			(layer "F.Fab")
		)
		(fp_line
			(start 0.12065 -0.2794)
			(end 0.12065 -0.3048)
			(stroke
				(width 0.1)
				(type default)
			)
			(layer "F.Fab")
		)
		(fp_line
			(start 0.12065 -0.3048)
			(end 0.67945 -0.3048)
			(stroke
				(width 0.1)
				(type default)
			)
			(layer "F.Fab")
		)
		(fp_line
			(start 0.67945 -0.3048)
			(end 0.67945 0.3048)
			(stroke
				(width 0.1)
				(type default)
			)
			(layer "F.Fab")
		)
		(fp_line
			(start -0.67945 -0.305054)
			(end -0.12065 -0.305054)
			(stroke
				(width 0.1)
				(type default)
			)
			(layer "F.Fab")
		)
		(fp_line
			(start -0.12065 -0.305054)
			(end -0.12065 -0.2794)
			(stroke
				(width 0.1)
				(type default)
			)
			(layer "F.Fab")
		)
		(pad "1" smd circle
			(at -0.40005 0 270)
			(size 0 0)
			(layers "F.Cu" "F.Mask" "F.Paste")
			(net "SW_PVCCFA_EHV_FIVRA_CPU0_BOOT1_")
		)
		(pad "2" smd circle
			(at 0.40005 0 270)
			(size 0 0)
			(layers "F.Cu" "F.Mask" "F.Paste")
			(net "SW_PVCCFA_EHV_FIVRA_CPU0_BOOTR1")
		)
	)
)
